# S9S_MB_2U (Grand Teton) — schematic netlist excerpt (pin names and nets, part order shuffled) for the footprints in the layout excerpt that follows; sources: Cadence DE-HDL packaged netlist, KiCad conversion of 03242023_DA0F0TMBIJ0_F0T_Motherboard_J_brd_V01_OCP.brd

J8  SCONN288_ADR50017P087CC  SCONN288_ADR50017-P087CC IO  pkg DDR288S_1-1VXB  page 89
  VIN_BULK0  = P12V_S3_AUX_CPU0_NVDIMM
  RFU0  = TP_CHD_CPU0_DIMM2_FRU_0
  VIN_MGMT  = P3V3_AUX
  HSCL  = I3C_SPD_DDRABCD_CPU0_LVC1_SCL_7
  HSDA  = I3C_SPD_DDRABCD_CPU0_LVC1_SDA
  VSS0  = GND
  DQ0_A  = M_D_CPU0_SA_DQ<0>
  VSS1  = GND
  DQ1_A  = M_D_CPU0_SA_DQ<1>
  VSS2  = GND
  DQS0_A_T  = M_D_CPU0_SA_DQS_DP<0>
  DQS0_A_C  = M_D_CPU0_SA_DQS_DN<0>
  VSS3  = GND
  DQ4_A  = M_D_CPU0_SA_DQ<4>
  VSS4  = GND
  DQ5_A  = M_D_CPU0_SA_DQ<5>
  VSS5  = GND
  DQ8_A  = M_D_CPU0_SA_DQ<8>
  VSS6  = GND
  DQ9_A  = M_D_CPU0_SA_DQ<9>
  VSS7  = GND
  DQS1_A_T  = M_D_CPU0_SA_DQS_DP<1>
  DQS1_A_C  = M_D_CPU0_SA_DQS_DN<1>
  VSS8  = GND
  DQ12_A  = M_D_CPU0_SA_DQ<12>
  VSS9  = GND
  DQ13_A  = M_D_CPU0_SA_DQ<13>
  VSS10  = GND
  DQ16_A  = M_D_CPU0_SA_DQ<16>
  VSS11  = GND
  DQ17_A  = M_D_CPU0_SA_DQ<17>
  VSS12  = GND
  DQS2_A_T  = M_D_CPU0_SA_DQS_DP<2>
  DQS2_A_C  = M_D_CPU0_SA_DQS_DN<2>
  VSS13  = GND
  DQ20_A  = M_D_CPU0_SA_DQ<20>
  VSS14  = GND
  DQ21_A  = M_D_CPU0_SA_DQ<21>
  VSS15  = GND
  DQ24_A  = M_D_CPU0_SA_DQ<24>
  VSS16  = GND
  DQ25_A  = M_D_CPU0_SA_DQ<25>
  VSS17  = GND
  DQS3_A_T  = M_D_CPU0_SA_DQS_DP<3>
  DQS3_A_C  = M_D_CPU0_SA_DQS_DN<3>
  VSS18  = GND
  DQ28_A  = M_D_CPU0_SA_DQ<28>
  VSS19  = GND
  DQ29_A  = M_D_CPU0_SA_DQ<29>
  VSS20  = GND
  CB0_A  = M_D_CPU0_SA_CB<0>
  VSS21  = GND
  CB1_A  = M_D_CPU0_SA_CB<1>
  VSS22  = GND
  DQS4_A_T  = M_D_CPU0_SA_DQS_DP<4>
  DQS4_A_C  = M_D_CPU0_SA_DQS_DN<4>
  VSS23  = GND
  CB4_A  = M_D_CPU0_SA_CB<4>
  VSS24  = GND
  CB5_A  = M_D_CPU0_SA_CB<5>
  VSS25  = GND
  ALERT_N  = M_D_CPU0_ALERT_N
  VSS26  = GND
  CS0_A_N  = M_D_CPU0_SA_CS_N<2>
  VSS27  = GND
  CA0_A  = M_D_CPU0_SA_CA<0>
  VSS28  = GND
  CA2_A  = M_D_CPU0_SA_CA<2>
  VSS29  = GND
  CA4_A  = M_D_CPU0_SA_CA<4>
  VSS30  = GND
  CA6_A  = M_D_CPU0_SA_CA<6>
  VSS31  = GND
  PAR_A  = M_D_CPU0_SA_PAR
  VSS32  = GND
  CA0_B  = M_D_CPU0_SB_CA<0>
  VSS33  = GND
  CA2_B  = M_D_CPU0_SB_CA<2>
  VSS34  = GND
  CA4_B  = M_D_CPU0_SB_CA<4>
  VSS35  = GND
  CA6_B  = M_D_CPU0_SB_CA<6>
  VSS36  = GND
  CS0_B_N  = M_D_CPU0_SB_CS_N<2>
  VSS37  = GND
  \lbd||rsp_a_n\  = M_D_CPU0_SA_RSP<1>
  \lbs||rsp_b_n\  = M_D_CPU0_SB_RSP<1>
  VSS38  = GND
  CB4_B  = M_D_CPU0_SB_CB<4>
  VSS39  = GND
  CB5_B  = M_D_CPU0_SB_CB<5>
  VSS40  = GND
  \dqs9_b_t||tdqs9_b_t||dbi4_b_n\  = M_D_CPU0_SB_DQS_DP<9>
  \dqs9_b_c||tdqs9_b_c\  = M_D_CPU0_SB_DQS_DN<9>
  VSS41  = GND
  CB0_B  = M_D_CPU0_SB_CB<0>
  VSS42  = GND
  CB1_B  = M_D_CPU0_SB_CB<1>
  VSS43  = GND
  DQ0_B  = M_D_CPU0_SB_DQ<0>
  VSS44  = GND
  DQ1_B  = M_D_CPU0_SB_DQ<1>
  VSS45  = GND
  DQS0_B_T  = M_D_CPU0_SB_DQS_DP<0>
  DQS0_B_C  = M_D_CPU0_SB_DQS_DN<0>
  VSS46  = GND
  DQ4_B  = M_D_CPU0_SB_DQ<4>
  VSS47  = GND
  DQ5_B  = M_D_CPU0_SB_DQ<5>
  VSS48  = GND
  DQ8_B  = M_D_CPU0_SB_DQ<8>
  VSS49  = GND
  DQ9_B  = M_D_CPU0_SB_DQ<9>
  VSS50  = GND
  DQS1_B_T  = M_D_CPU0_SB_DQS_DP<1>
  DQS1_B_C  = M_D_CPU0_SB_DQS_DN<1>
  VSS51  = GND
  DQ12_B  = M_D_CPU0_SB_DQ<12>
  VSS52  = GND
  DQ13_B  = M_D_CPU0_SB_DQ<13>
  VSS53  = GND
  DQ16_B  = M_D_CPU0_SB_DQ<16>
  VSS54  = GND
  DQ17_B  = M_D_CPU0_SB_DQ<17>
  VSS55  = GND
  DQS2_B_T  = M_D_CPU0_SB_DQS_DP<2>
  DQS2_B_C  = M_D_CPU0_SB_DQS_DN<2>
  VSS56  = GND
  DQ20_B  = M_D_CPU0_SB_DQ<20>
  VSS57  = GND
  DQ21_B  = M_D_CPU0_SB_DQ<21>
  VSS58  = GND
  DQ24_B  = M_D_CPU0_SB_DQ<24>
  VSS59  = GND
  DQ25_B  = M_D_CPU0_SB_DQ<25>
  VSS60  = GND
  DQS3_B_T  = M_D_CPU0_SB_DQS_DP<3>
  DQS3_B_C  = M_D_CPU0_SB_DQS_DN<3>
  VSS61  = GND
  DQ28_B  = M_D_CPU0_SB_DQ<28>
  VSS62  = GND
  DQ29_B  = M_D_CPU0_SB_DQ<29>
  VSS63  = GND
  RFU1  = TP_CHD_CPU0_DIMM2_FRU_1
  VIN_BULK1  = P12V_S3_AUX_CPU0_NVDIMM
  VIN_BULK2  = P12V_S3_AUX_CPU0_NVDIMM
  \pwr_good||fail_n\  = PWRGD_CHD_CPU0_DIMM2
  HSA  = PD_CHD_CPU0_DIMM2_SAA
  RFU2  = TP_CHD_CPU0_DIMM2_FRU_2
  RFU3  = TP_CHD_CPU0_DIMM2_FRU_3
  VSS64  = GND
  DQ2_A  = M_D_CPU0_SA_DQ<2>
  VSS65  = GND
  DQ3_A  = M_D_CPU0_SA_DQ<3>
  VSS66  = GND
  \dqs5_a_c||tdqs5_a_c||dqs5_a_t||tdqs5_a_t\  = M_D_CPU0_SA_DQS_DN<5>
  \dqs5_a_t||tdqs5_a_t\  = M_D_CPU0_SA_DQS_DP<5>
  VSS67  = GND
  DQ6_A  = M_D_CPU0_SA_DQ<6>
  VSS68  = GND
  DQ7_A  = M_D_CPU0_SA_DQ<7>
  VSS69  = GND
  DQ10_A  = M_D_CPU0_SA_DQ<10>
  VSS70  = GND
  DQ11_A  = M_D_CPU0_SA_DQ<11>
  VSS71  = GND
  \dqs6_a_c||tdqs6_a_c||dqs6_a_t||tdqs6_a_t\  = M_D_CPU0_SA_DQS_DN<6>
  \dqs6_a_t||tdqs6_a_t\  = M_D_CPU0_SA_DQS_DP<6>
  VSS72  = GND
  DQ14_A  = M_D_CPU0_SA_DQ<14>
  VSS73  = GND
  DQ15_A  = M_D_CPU0_SA_DQ<15>
  VSS74  = GND
  DQ18_A  = M_D_CPU0_SA_DQ<18>
  VSS75  = GND
  DQ19_A  = M_D_CPU0_SA_DQ<19>
  VSS76  = GND
  \dqs7_a_c||tdqs7_a_c\  = M_D_CPU0_SA_DQS_DN<7>
  \dqs7_a_t||tdqs7_a_t\  = M_D_CPU0_SA_DQS_DP<7>
  VSS77  = GND
  DQ22_A  = M_D_CPU0_SA_DQ<22>
  VSS78  = GND
  DQ23_A  = M_D_CPU0_SA_DQ<23>
  VSS79  = GND
  DQ26_A  = M_D_CPU0_SA_DQ<26>
  VSS80  = GND
  DQ27_A  = M_D_CPU0_SA_DQ<27>
  VSS81  = GND
  \dqs8_a_c||tdqs8_a_c\  = M_D_CPU0_SA_DQS_DN<8>
  \dqs8_a_t||tdqs8_a_t\  = M_D_CPU0_SA_DQS_DP<8>
  VSS82  = GND
  DQ30_A  = M_D_CPU0_SA_DQ<30>
  VSS83  = GND
  DQ31_A  = M_D_CPU0_SA_DQ<31>
  VSS84  = GND
  CB2_A  = M_D_CPU0_SA_CB<2>
  VSS85  = GND
  CB3_A  = M_D_CPU0_SA_CB<3>
  VSS86  = GND
  \dqs9_a_c||tdqs9_a_c\  = M_D_CPU0_SA_DQS_DN<9>
  \dqs9_a_t||tdqs9_a_t\  = M_D_CPU0_SA_DQS_DP<9>
  VSS87  = GND
  CB6_A  = M_D_CPU0_SA_CB<6>
  VSS88  = GND
  CB7_A  = M_D_CPU0_SA_CB<7>
  VSS89  = GND
  RESET_N  = RST_M_CD_CPU0_FPGA_N
  VSS90  = GND
  CS1_A_N  = M_D_CPU0_SA_CS_N<3>
  VSS91  = GND
  CA1_A  = M_D_CPU0_SA_CA<1>
  VSS92  = GND
  CA3_A  = M_D_CPU0_SA_CA<3>
  VSS93  = GND
  CA5_A  = M_D_CPU0_SA_CA<5>
  VSS94  = GND
  CK_T  = M_D_CPU0_CLK_DP<1>
  CK_C  = M_D_CPU0_CLK_DN<1>
  VSS95  = GND
  RFU4  = TP_CHD_CPU0_DIMM2_FRU_4
  CA1_B  = M_D_CPU0_SB_CA<1>
  VSS96  = GND
  CA3_B  = M_D_CPU0_SB_CA<3>
  VSS97  = GND
  CA5_B  = M_D_CPU0_SB_CA<5>
  VSS98  = GND
  PAR_B  = M_D_CPU0_SB_PAR
  VSS99  = GND
  CS1_B_N  = M_D_CPU0_SB_CS_N<3>
  VSS100  = GND
  RFU5  = TP_CHD_CPU0_DIMM2_FRU_5
  RFU6  = TP_CHD_CPU0_DIMM2_FRU_6
  VSS101  = GND
  CB6_B  = M_D_CPU0_SB_CB<6>
  VSS102  = GND
  CB7_B  = M_D_CPU0_SB_CB<7>
  VSS103  = GND
  DQS4_B_C  = M_D_CPU0_SB_DQS_DN<4>
  DQS4_B_T  = M_D_CPU0_SB_DQS_DP<4>
  VSS104  = GND
  CB2_B  = M_D_CPU0_SB_CB<2>
  VSS105  = GND
  CB3_B  = M_D_CPU0_SB_CB<3>
  VSS106  = GND
  DQ2_B  = M_D_CPU0_SB_DQ<2>
  VSS107  = GND
  DQ3_B  = M_D_CPU0_SB_DQ<3>
  VSS108  = GND
  \dqs5_b_c||tdqs5_b_c\  = M_D_CPU0_SB_DQS_DN<5>
  \dqs5_b_t||tdqs5_b_t\  = M_D_CPU0_SB_DQS_DP<5>
  VSS109  = GND
  DQ6_B  = M_D_CPU0_SB_DQ<6>
  VSS110  = GND
  DQ7_B  = M_D_CPU0_SB_DQ<7>
  VSS111  = GND
  DQ10_B  = M_D_CPU0_SB_DQ<10>
  VSS112  = GND
  DQ11_B  = M_D_CPU0_SB_DQ<11>
  VSS113  = GND
  \dqs6_b_c||tdqs6_b_c\  = M_D_CPU0_SB_DQS_DN<6>
  \dqs6_b_t||tdqs6_b_t\  = M_D_CPU0_SB_DQS_DP<6>
  VSS114  = GND
  DQ14_B  = M_D_CPU0_SB_DQ<14>
  VSS115  = GND
  DQ15_B  = M_D_CPU0_SB_DQ<15>
  VSS116  = GND
  DQ18_B  = M_D_CPU0_SB_DQ<18>
  VSS117  = GND
  DQ19_B  = M_D_CPU0_SB_DQ<19>
  VSS118  = GND
  \dqs7_b_c||tdqs7_b_c\  = M_D_CPU0_SB_DQS_DN<7>
  \dqs7_b_t||tdqs7_b_t\  = M_D_CPU0_SB_DQS_DP<7>
  VSS119  = GND
  DQ22_B  = M_D_CPU0_SB_DQ<22>
  VSS120  = GND
  DQ23_B  = M_D_CPU0_SB_DQ<23>
  VSS121  = GND
  DQ26_B  = M_D_CPU0_SB_DQ<26>
  VSS122  = GND
  DQ27_B  = M_D_CPU0_SB_DQ<27>
  VSS123  = GND
  \dqs8_b_c||tdqs8_b_c\  = M_D_CPU0_SB_DQS_DN<8>
  \dqs8_b_t||tdqs8_b_t\  = M_D_CPU0_SB_DQS_DP<8>
  VSS124  = GND
  DQ30_B  = M_D_CPU0_SB_DQ<30>
  VSS125  = GND
  DQ31_B  = M_D_CPU0_SB_DQ<31>
  VSS126  = GND
  G1  = GND
  G2  = GND
  G3  = GND

(kicad_pcb
	(version 20260206)
	(generator "pcbnew")
	(generator_version "10.0")
	(general
		(thickness 1.6)
		(legacy_teardrops no)
	)
	(paper "A4")
	(title_block
		(title "03242023_DA0F0TMBIJ0_F0T_Motherboard_J_brd_V01_OCP.brd")
		(comment 1 "Grand Teton / footprint 652 of 6105 (J8), pads 275-291 of 291")
	)
	(layers
		(0 "F.Cu" signal "TOP")
		(4 "In1.Cu" signal "GND")
		(6 "In2.Cu" signal "IN1")
		(8 "In3.Cu" signal "GND1")
		(10 "In4.Cu" signal "IN2")
		(12 "In5.Cu" signal "GND2")
		(14 "In6.Cu" signal "IN3")
		(16 "In7.Cu" signal "GND3")
		(18 "In8.Cu" signal "VCC")
		(20 "In9.Cu" signal "VCC1")
		(22 "In10.Cu" signal "GND4")
		(24 "In11.Cu" signal "IN4")
		(26 "In12.Cu" signal "GND5")
		(28 "In13.Cu" signal "IN5")
		(30 "In14.Cu" signal "GND6")
		(32 "In15.Cu" signal "IN6")
		(34 "In16.Cu" signal "GND7")
		(2 "B.Cu" signal "BOTTOM")
		(9 "F.Adhes" user "F.Adhesive")
		(11 "B.Adhes" user "B.Adhesive")
		(13 "F.Paste" user "Package Geometry/Pastemask Top")
		(15 "B.Paste" user "Package Geometry/Pastemask Bottom")
		(5 "F.SilkS" user "Ref Des/Silkscreen Top")
		(7 "B.SilkS" user "Ref Des/Silkscreen Bottom")
		(1 "F.Mask" user "Board Geometry/Soldermask Top")
		(3 "B.Mask" user "Board Geometry/Soldermask Bottom")
		(17 "Dwgs.User" user "User.Drawings")
		(19 "Cmts.User" user "User.Comments")
		(21 "Eco1.User" user "User.Eco1")
		(23 "Eco2.User" user "User.Eco2")
		(25 "Edge.Cuts" user "Board Geometry/Outline")
		(27 "Margin" user)
		(31 "F.CrtYd" user "Package Geometry/Place Bound Top")
		(29 "B.CrtYd" user "Package Geometry/Place Bound Bottom")
		(35 "F.Fab" user "Ref Des/Assembly Top")
		(33 "B.Fab" user "Ref Des/Assembly Bottom")
	)
	(footprint ""
		(layer "F.Cu")
		(at 265.674348 -258.091686)
		(property "Reference" "J8"
			(at -3.683 -81.702148 0)
			(unlocked yes)
			(layer "F.SilkS")
			(effects
				(font
					(size 0.7874 0.5842)
					(thickness 0.1524)
				)
				(justify left)
			)
		)
		(property "Value" ""
			(at 0 0 0)
			(layer "F.Fab")
			(effects
				(font
					(size 1.27 1.27)
				)
			)
		)
		(duplicate_pad_numbers_are_jumpers no)
		(pad "275" smd rect
			(at 2.050034 52.274978 270)
			(size 0.519938 1.4986)
			(layers "F.Cu" "F.Mask" "F.Paste")
			(net "GND")
		)
		(pad "276" smd rect
			(at 2.050034 53.125116 270)
			(size 0.519938 1.4986)
			(layers "F.Cu" "F.Mask" "F.Paste")
			(net "M_D_CPU0_SB_DQ<23>")
		)
		(pad "277" smd rect
			(at 2.050034 53.975 270)
			(size 0.519938 1.4986)
			(layers "F.Cu" "F.Mask" "F.Paste")
			(net "GND")
		)
		(pad "278" smd rect
			(at 2.050034 54.824884 270)
			(size 0.519938 1.4986)
			(layers "F.Cu" "F.Mask" "F.Paste")
			(net "M_D_CPU0_SB_DQ<26>")
		)
		(pad "279" smd rect
			(at 2.050034 55.675022 270)
			(size 0.519938 1.4986)
			(layers "F.Cu" "F.Mask" "F.Paste")
			(net "GND")
		)
		(pad "280" smd rect
			(at 2.050034 56.524906 270)
			(size 0.519938 1.4986)
			(layers "F.Cu" "F.Mask" "F.Paste")
			(net "M_D_CPU0_SB_DQ<27>")
		)
		(pad "281" smd rect
			(at 2.050034 57.375044 270)
			(size 0.519938 1.4986)
			(layers "F.Cu" "F.Mask" "F.Paste")
			(net "GND")
		)
		(pad "282" smd rect
			(at 2.050034 58.224928 270)
			(size 0.519938 1.4986)
			(layers "F.Cu" "F.Mask" "F.Paste")
			(net "M_D_CPU0_SB_DQS_DN<8>")
		)
		(pad "283" smd rect
			(at 2.050034 59.075066 270)
			(size 0.519938 1.4986)
			(layers "F.Cu" "F.Mask" "F.Paste")
			(net "M_D_CPU0_SB_DQS_DP<8>")
		)
		(pad "284" smd rect
			(at 2.050034 59.92495 270)
			(size 0.519938 1.4986)
			(layers "F.Cu" "F.Mask" "F.Paste")
			(net "GND")
		)
		(pad "285" smd rect
			(at 2.050034 60.775088 270)
			(size 0.519938 1.4986)
			(layers "F.Cu" "F.Mask" "F.Paste")
			(net "M_D_CPU0_SB_DQ<30>")
		)
		(pad "286" smd rect
			(at 2.050034 61.624972 270)
			(size 0.519938 1.4986)
			(layers "F.Cu" "F.Mask" "F.Paste")
			(net "GND")
		)
		(pad "287" smd rect
			(at 2.050034 62.47511 270)
			(size 0.519938 1.4986)
			(layers "F.Cu" "F.Mask" "F.Paste")
			(net "M_D_CPU0_SB_DQ<31>")
		)
		(pad "288" smd rect
			(at 2.050034 63.324994 270)
			(size 0.519938 1.4986)
			(layers "F.Cu" "F.Mask" "F.Paste")
			(net "GND")
		)
		(pad "G1" thru_hole oval
			(at 0 -68.97497)
			(size 2.8194 1.5748)
			(drill oval 2.4384 1.1938)
			(layers "*.Cu" "*.Mask")
			(remove_unused_layers no)
			(net "GND")
			(clearance 0.127)
			(thermal_gap 0.127)
		)
		(pad "G2" thru_hole oval
			(at 0 3.875024)
			(size 2.8194 1.5748)
			(drill oval 2.4384 1.1938)
			(layers "*.Cu" "*.Mask")
			(remove_unused_layers no)
			(net "GND")
			(clearance 0.127)
			(thermal_gap 0.127)
		)
		(pad "G3" thru_hole oval
			(at 0 68.97497)
			(size 2.8194 1.5748)
			(drill oval 2.4384 1.1938)
			(layers "*.Cu" "*.Mask")
			(remove_unused_layers no)
			(net "GND")
			(clearance 0.127)
			(thermal_gap 0.127)
		)
	)
)
